(kicad_pcb
	(version 20260206)
	(generator "pcbnew")
	(generator_version "10.0")
	(general
		(thickness 1.6)
		(legacy_teardrops no)
	)
	(paper "A4")
	(title_block
		(title "04192023_DAF0TMB3IC0_F0TG_MB_C_brd_V02_OCP.brd")
		(comment 1 "Grand Teton / footprints 4335-4341 of 8354")
	)
	(layers
		(0 "F.Cu" signal "TOP")
		(4 "In1.Cu" signal "GND")
		(6 "In2.Cu" signal "IN1")
		(8 "In3.Cu" signal "GND1")
		(10 "In4.Cu" signal "IN2")
		(12 "In5.Cu" signal "GND2")
		(14 "In6.Cu" signal "IN3")
		(16 "In7.Cu" signal "GND3")
		(18 "In8.Cu" signal "VCC")
		(20 "In9.Cu" signal "VCC1")
		(22 "In10.Cu" signal "GND4")
		(24 "In11.Cu" signal "IN4")
		(26 "In12.Cu" signal "GND5")
		(28 "In13.Cu" signal "IN5")
		(30 "In14.Cu" signal "GND6")
		(32 "In15.Cu" signal "IN6")
		(34 "In16.Cu" signal "GND7")
		(2 "B.Cu" signal "BOTTOM")
		(9 "F.Adhes" user "F.Adhesive")
		(11 "B.Adhes" user "B.Adhesive")
		(13 "F.Paste" user "Package Geometry/Pastemask Top")
		(15 "B.Paste" user "Package Geometry/Pastemask Bottom")
		(5 "F.SilkS" user "Ref Des/Silkscreen Top")
		(7 "B.SilkS" user "Ref Des/Silkscreen Bottom")
		(1 "F.Mask" user "Board Geometry/Soldermask Top")
		(3 "B.Mask" user "Board Geometry/Soldermask Bottom")
		(17 "Dwgs.User" user "User.Drawings")
		(19 "Cmts.User" user "User.Comments")
		(21 "Eco1.User" user "User.Eco1")
		(23 "Eco2.User" user "User.Eco2")
		(25 "Edge.Cuts" user "Board Geometry/Outline")
		(27 "Margin" user)
		(31 "F.CrtYd" user "Package Geometry/Place Bound Top")
		(29 "B.CrtYd" user "Package Geometry/Place Bound Bottom")
		(35 "F.Fab" user "Ref Des/Assembly Top")
		(33 "B.Fab" user "Ref Des/Assembly Bottom")
	)
	(footprint ""
		(layer "F.Cu")
		(at 170.8404 -333.375508 180)
		(property "Reference" "PR229"
			(at 0 0 180)
			(layer "F.SilkS")
			(hide yes)
			(effects
				(font
					(size 1.27 1.27)
				)
			)
		)
		(property "Value" ""
			(at 0 0 180)
			(layer "F.Fab")
			(effects
				(font
					(size 1.27 1.27)
				)
			)
		)
		(duplicate_pad_numbers_are_jumpers no)
		(fp_line
			(start 0.7874 0.4064)
			(end -0.7874 0.4064)
			(stroke
				(width 0.1524)
				(type default)
			)
			(layer "F.SilkS")
		)
		(fp_line
			(start 0.7874 -0.4064)
			(end 0.7874 0.4064)
			(stroke
				(width 0.1524)
				(type default)
			)
			(layer "F.SilkS")
		)
		(fp_line
			(start -0.7874 0.4064)
			(end -0.7874 -0.4064)
			(stroke
				(width 0.1524)
				(type default)
			)
			(layer "F.SilkS")
		)
		(fp_line
			(start -0.7874 -0.4064)
			(end 0.7874 -0.4064)
			(stroke
				(width 0.1524)
				(type default)
			)
			(layer "F.SilkS")
		)
		(fp_line
			(start 0.67945 0.3048)
			(end 0.120396 0.3048)
			(stroke
				(width 0.1)
				(type default)
			)
			(layer "F.Fab")
		)
		(fp_line
			(start 0.67945 -0.3048)
			(end 0.67945 0.3048)
			(stroke
				(width 0.1)
				(type default)
			)
			(layer "F.Fab")
		)
		(fp_line
			(start 0.12065 -0.2794)
			(end 0.12065 -0.3048)
			(stroke
				(width 0.1)
				(type default)
			)
			(layer "F.Fab")
		)
		(fp_line
			(start 0.12065 -0.3048)
			(end 0.67945 -0.3048)
			(stroke
				(width 0.1)
				(type default)
			)
			(layer "F.Fab")
		)
		(fp_line
			(start 0.120396 0.3048)
			(end 0.120396 0.2794)
			(stroke
				(width 0.1)
				(type default)
			)
			(layer "F.Fab")
		)
		(fp_line
			(start 0.120396 0.2794)
			(end -0.12065 0.2794)
			(stroke
				(width 0.1)
				(type default)
			)
			(layer "F.Fab")
		)
		(fp_line
			(start -0.12065 0.3048)
			(end -0.67945 0.3048)
			(stroke
				(width 0.1)
				(type default)
			)
			(layer "F.Fab")
		)
		(fp_line
			(start -0.12065 0.2794)
			(end -0.12065 0.3048)
			(stroke
				(width 0.1)
				(type default)
			)
			(layer "F.Fab")
		)
		(fp_line
			(start -0.12065 -0.2794)
			(end 0.12065 -0.2794)
			(stroke
				(width 0.1)
				(type default)
			)
			(layer "F.Fab")
		)
		(fp_line
			(start -0.12065 -0.305054)
			(end -0.12065 -0.2794)
			(stroke
				(width 0.1)
				(type default)
			)
			(layer "F.Fab")
		)
		(fp_line
			(start -0.67945 0.3048)
			(end -0.67945 -0.305054)
			(stroke
				(width 0.1)
				(type default)
			)
			(layer "F.Fab")
		)
		(fp_line
			(start -0.67945 -0.305054)
			(end -0.12065 -0.305054)
			(stroke
				(width 0.1)
				(type default)
			)
			(layer "F.Fab")
		)
		(pad "1" smd circle
			(at -0.40005 0 180)
			(size 0 0)
			(layers "F.Cu" "F.Mask" "F.Paste")
			(net "PVDD11_S3_P1")
		)
		(pad "2" smd circle
			(at 0.40005 0 180)
			(size 0 0)
			(layers "F.Cu" "F.Mask" "F.Paste")
			(net "VSENSE_PVDD11_S3_P1_DP")
		)
	)
	(footprint ""
		(layer "F.Cu")
		(at 197.269608 -113.625376 180)
		(property "Reference" "R283"
			(at 0 0 180)
			(layer "F.SilkS")
			(hide yes)
			(effects
				(font
					(size 1.27 1.27)
				)
			)
		)
		(property "Value" ""
			(at 0 0 180)
			(layer "F.Fab")
			(effects
				(font
					(size 1.27 1.27)
				)
			)
		)
		(duplicate_pad_numbers_are_jumpers no)
		(fp_line
			(start 0.7874 0.4064)
			(end -0.7874 0.4064)
			(stroke
				(width 0.1524)
				(type default)
			)
			(layer "F.SilkS")
		)
		(fp_line
			(start 0.7874 -0.4064)
			(end 0.7874 0.4064)
			(stroke
				(width 0.1524)
				(type default)
			)
			(layer "F.SilkS")
		)
		(fp_line
			(start -0.7874 0.4064)
			(end -0.7874 -0.4064)
			(stroke
				(width 0.1524)
				(type default)
			)
			(layer "F.SilkS")
		)
		(fp_line
			(start -0.7874 -0.4064)
			(end 0.7874 -0.4064)
			(stroke
				(width 0.1524)
				(type default)
			)
			(layer "F.SilkS")
		)
		(fp_line
			(start 0.67945 0.3048)
			(end 0.120396 0.3048)
			(stroke
				(width 0.1)
				(type default)
			)
			(layer "F.Fab")
		)
		(fp_line
			(start 0.67945 -0.3048)
			(end 0.67945 0.3048)
			(stroke
				(width 0.1)
				(type default)
			)
			(layer "F.Fab")
		)
		(fp_line
			(start 0.12065 -0.2794)
			(end 0.12065 -0.3048)
			(stroke
				(width 0.1)
				(type default)
			)
			(layer "F.Fab")
		)
		(fp_line
			(start 0.12065 -0.3048)
			(end 0.67945 -0.3048)
			(stroke
				(width 0.1)
				(type default)
			)
			(layer "F.Fab")
		)
		(fp_line
			(start 0.120396 0.3048)
			(end 0.120396 0.2794)
			(stroke
				(width 0.1)
				(type default)
			)
			(layer "F.Fab")
		)
		(fp_line
			(start 0.120396 0.2794)
			(end -0.12065 0.2794)
			(stroke
				(width 0.1)
				(type default)
			)
			(layer "F.Fab")
		)
		(fp_line
			(start -0.12065 0.3048)
			(end -0.67945 0.3048)
			(stroke
				(width 0.1)
				(type default)
			)
			(layer "F.Fab")
		)
		(fp_line
			(start -0.12065 0.2794)
			(end -0.12065 0.3048)
			(stroke
				(width 0.1)
				(type default)
			)
			(layer "F.Fab")
		)
		(fp_line
			(start -0.12065 -0.2794)
			(end 0.12065 -0.2794)
			(stroke
				(width 0.1)
				(type default)
			)
			(layer "F.Fab")
		)
		(fp_line
			(start -0.12065 -0.305054)
			(end -0.12065 -0.2794)
			(stroke
				(width 0.1)
				(type default)
			)
			(layer "F.Fab")
		)
		(fp_line
			(start -0.67945 0.3048)
			(end -0.67945 -0.305054)
			(stroke
				(width 0.1)
				(type default)
			)
			(layer "F.Fab")
		)
		(fp_line
			(start -0.67945 -0.305054)
			(end -0.12065 -0.305054)
			(stroke
				(width 0.1)
				(type default)
			)
			(layer "F.Fab")
		)
		(pad "1" smd circle
			(at -0.40005 0 180)
			(size 0 0)
			(layers "F.Cu" "F.Mask" "F.Paste")
			(net "PWRGD_PVDDIO_P1")
		)
		(pad "2" smd circle
			(at 0.40005 0 180)
			(size 0 0)
			(layers "F.Cu" "F.Mask" "F.Paste")
			(net "FM_PWRGD_PVDDIO_P1")
		)
	)
	(footprint ""
		(layer "F.Cu")
		(at 327.46061 -339.63991 90)
		(property "Reference" "PR81"
			(at 0 0 90)
			(layer "F.SilkS")
			(hide yes)
			(effects
				(font
					(size 1.27 1.27)
				)
			)
		)
		(property "Value" ""
			(at 0 0 90)
			(layer "F.Fab")
			(effects
				(font
					(size 1.27 1.27)
				)
			)
		)
		(duplicate_pad_numbers_are_jumpers no)
		(fp_line
			(start 0.7874 -0.4064)
			(end 0.7874 0.4064)
			(stroke
				(width 0.1524)
				(type default)
			)
			(layer "F.SilkS")
		)
		(fp_line
			(start -0.7874 -0.4064)
			(end 0.7874 -0.4064)
			(stroke
				(width 0.1524)
				(type default)
			)
			(layer "F.SilkS")
		)
		(fp_line
			(start 0.7874 0.4064)
			(end -0.7874 0.4064)
			(stroke
				(width 0.1524)
				(type default)
			)
			(layer "F.SilkS")
		)
		(fp_line
			(start -0.7874 0.4064)
			(end -0.7874 -0.4064)
			(stroke
				(width 0.1524)
				(type default)
			)
			(layer "F.SilkS")
		)
		(fp_line
			(start -0.12065 -0.305054)
			(end -0.12065 -0.2794)
			(stroke
				(width 0.1)
				(type default)
			)
			(layer "F.Fab")
		)
		(fp_line
			(start -0.67945 -0.305054)
			(end -0.12065 -0.305054)
			(stroke
				(width 0.1)
				(type default)
			)
			(layer "F.Fab")
		)
		(fp_line
			(start 0.67945 -0.3048)
			(end 0.67945 0.3048)
			(stroke
				(width 0.1)
				(type default)
			)
			(layer "F.Fab")
		)
		(fp_line
			(start 0.12065 -0.3048)
			(end 0.67945 -0.3048)
			(stroke
				(width 0.1)
				(type default)
			)
			(layer "F.Fab")
		)
		(fp_line
			(start 0.12065 -0.2794)
			(end 0.12065 -0.3048)
			(stroke
				(width 0.1)
				(type default)
			)
			(layer "F.Fab")
		)
		(fp_line
			(start -0.12065 -0.2794)
			(end 0.12065 -0.2794)
			(stroke
				(width 0.1)
				(type default)
			)
			(layer "F.Fab")
		)
		(fp_line
			(start 0.120396 0.2794)
			(end -0.12065 0.2794)
			(stroke
				(width 0.1)
				(type default)
			)
			(layer "F.Fab")
		)
		(fp_line
			(start -0.12065 0.2794)
			(end -0.12065 0.3048)
			(stroke
				(width 0.1)
				(type default)
			)
			(layer "F.Fab")
		)
		(fp_line
			(start 0.67945 0.3048)
			(end 0.120396 0.3048)
			(stroke
				(width 0.1)
				(type default)
			)
			(layer "F.Fab")
		)
		(fp_line
			(start 0.120396 0.3048)
			(end 0.120396 0.2794)
			(stroke
				(width 0.1)
				(type default)
			)
			(layer "F.Fab")
		)
		(fp_line
			(start -0.12065 0.3048)
			(end -0.67945 0.3048)
			(stroke
				(width 0.1)
				(type default)
			)
			(layer "F.Fab")
		)
		(fp_line
			(start -0.67945 0.3048)
			(end -0.67945 -0.305054)
			(stroke
				(width 0.1)
				(type default)
			)
			(layer "F.Fab")
		)
		(pad "1" smd circle
			(at -0.40005 0 90)
			(size 0 0)
			(layers "F.Cu" "F.Mask" "F.Paste")
			(net "SW_PVDDCR_CPU1_P0_BOOT2")
		)
		(pad "2" smd circle
			(at 0.40005 0 90)
			(size 0 0)
			(layers "F.Cu" "F.Mask" "F.Paste")
			(net "SW_PVDDCR_CPU1_P0_BOOT2_R")
		)
	)
	(footprint ""
		(layer "F.Cu")
		(at 152.849834 -322.731892 180)
		(property "Reference" "R584"
			(at 0 0 180)
			(layer "F.SilkS")
			(hide yes)
			(effects
				(font
					(size 1.27 1.27)
				)
			)
		)
		(property "Value" ""
			(at 0 0 180)
			(layer "F.Fab")
			(effects
				(font
					(size 1.27 1.27)
				)
			)
		)
		(duplicate_pad_numbers_are_jumpers no)
		(fp_line
			(start 0.7874 0.4064)
			(end -0.7874 0.4064)
			(stroke
				(width 0.1524)
				(type default)
			)
			(layer "F.SilkS")
		)
		(fp_line
			(start 0.7874 -0.4064)
			(end 0.7874 0.4064)
			(stroke
				(width 0.1524)
				(type default)
			)
			(layer "F.SilkS")
		)
		(fp_line
			(start -0.7874 0.4064)
			(end -0.7874 -0.4064)
			(stroke
				(width 0.1524)
				(type default)
			)
			(layer "F.SilkS")
		)
		(fp_line
			(start -0.7874 -0.4064)
			(end 0.7874 -0.4064)
			(stroke
				(width 0.1524)
				(type default)
			)
			(layer "F.SilkS")
		)
		(fp_line
			(start 0.67945 0.3048)
			(end 0.120396 0.3048)
			(stroke
				(width 0.1)
				(type default)
			)
			(layer "F.Fab")
		)
		(fp_line
			(start 0.67945 -0.3048)
			(end 0.67945 0.3048)
			(stroke
				(width 0.1)
				(type default)
			)
			(layer "F.Fab")
		)
		(fp_line
			(start 0.12065 -0.2794)
			(end 0.12065 -0.3048)
			(stroke
				(width 0.1)
				(type default)
			)
			(layer "F.Fab")
		)
		(fp_line
			(start 0.12065 -0.3048)
			(end 0.67945 -0.3048)
			(stroke
				(width 0.1)
				(type default)
			)
			(layer "F.Fab")
		)
		(fp_line
			(start 0.120396 0.3048)
			(end 0.120396 0.2794)
			(stroke
				(width 0.1)
				(type default)
			)
			(layer "F.Fab")
		)
		(fp_line
			(start 0.120396 0.2794)
			(end -0.12065 0.2794)
			(stroke
				(width 0.1)
				(type default)
			)
			(layer "F.Fab")
		)
		(fp_line
			(start -0.12065 0.3048)
			(end -0.67945 0.3048)
			(stroke
				(width 0.1)
				(type default)
			)
			(layer "F.Fab")
		)
		(fp_line
			(start -0.12065 0.2794)
			(end -0.12065 0.3048)
			(stroke
				(width 0.1)
				(type default)
			)
			(layer "F.Fab")
		)
		(fp_line
			(start -0.12065 -0.2794)
			(end 0.12065 -0.2794)
			(stroke
				(width 0.1)
				(type default)
			)
			(layer "F.Fab")
		)
		(fp_line
			(start -0.12065 -0.305054)
			(end -0.12065 -0.2794)
			(stroke
				(width 0.1)
				(type default)
			)
			(layer "F.Fab")
		)
		(fp_line
			(start -0.67945 0.3048)
			(end -0.67945 -0.305054)
			(stroke
				(width 0.1)
				(type default)
			)
			(layer "F.Fab")
		)
		(fp_line
			(start -0.67945 -0.305054)
			(end -0.12065 -0.305054)
			(stroke
				(width 0.1)
				(type default)
			)
			(layer "F.Fab")
		)
		(pad "1" smd circle
			(at -0.40005 0 180)
			(size 0 0)
			(layers "F.Cu" "F.Mask" "F.Paste")
			(net "GND")
		)
		(pad "2" smd circle
			(at 0.40005 0 180)
			(size 0 0)
			(layers "F.Cu" "F.Mask" "F.Paste")
			(net "RST_CPU1_RSMRST_N")
		)
	)
	(footprint ""
		(layer "F.Cu")
		(at 387.425692 -381.41783 -90)
		(property "Reference" "C878"
			(at 0 0 270)
			(layer "F.SilkS")
			(hide yes)
			(effects
				(font
					(size 1.27 1.27)
				)
			)
		)
		(property "Value" ""
			(at 0 0 270)
			(layer "F.Fab")
			(effects
				(font
					(size 1.27 1.27)
				)
			)
		)
		(duplicate_pad_numbers_are_jumpers no)
		(fp_line
			(start -0.299974 0.150114)
			(end -0.299974 -0.150114)
			(stroke
				(width 0.1)
				(type default)
			)
			(layer "F.Fab")
		)
		(fp_line
			(start 0.299974 0.150114)
			(end -0.299974 0.150114)
			(stroke
				(width 0.1)
				(type default)
			)
			(layer "F.Fab")
		)
		(fp_line
			(start -0.299974 -0.150114)
			(end 0.299974 -0.150114)
			(stroke
				(width 0.1)
				(type default)
			)
			(layer "F.Fab")
		)
		(fp_line
			(start 0.299974 -0.150114)
			(end 0.299974 0.150114)
			(stroke
				(width 0.1)
				(type default)
			)
			(layer "F.Fab")
		)
		(pad "1" smd rect
			(at -0.2667 0 270)
			(size 0.3048 0.381)
			(layers "F.Cu" "F.Mask" "F.Paste")
			(net "P5E_CPU0_P3_TX_C_DN<11>")
		)
		(pad "2" smd rect
			(at 0.2667 0 270)
			(size 0.3048 0.381)
			(layers "F.Cu" "F.Mask" "F.Paste")
			(net "P5E_CPU0_P3_TX_DN<11>")
		)
	)
	(footprint ""
		(layer "F.Cu")
		(at 85.96757 -180.078634 -90)
		(property "Reference" "PC256"
			(at 0 0 270)
			(layer "F.SilkS")
			(hide yes)
			(effects
				(font
					(size 1.27 1.27)
				)
			)
		)
		(property "Value" ""
			(at 0 0 270)
			(layer "F.Fab")
			(effects
				(font
					(size 1.27 1.27)
				)
			)
		)
		(duplicate_pad_numbers_are_jumpers no)
		(fp_line
			(start -0.7874 0.4064)
			(end -0.7874 -0.4064)
			(stroke
				(width 0.1524)
				(type default)
			)
			(layer "F.SilkS")
		)
		(fp_line
			(start -0.134366 0.4064)
			(end -0.7874 0.4064)
			(stroke
				(width 0.1524)
				(type default)
			)
			(layer "F.SilkS")
		)
		(fp_line
			(start 0.7874 0.4064)
			(end 0.500634 0.4064)
			(stroke
				(width 0.1524)
				(type default)
			)
			(layer "F.SilkS")
		)
		(fp_line
			(start -0.7874 -0.4064)
			(end 0.7874 -0.4064)
			(stroke
				(width 0.1524)
				(type default)
			)
			(layer "F.SilkS")
		)
		(fp_line
			(start 0.7874 -0.4064)
			(end 0.7874 0.4064)
			(stroke
				(width 0.1524)
				(type default)
			)
			(layer "F.SilkS")
		)
		(fp_line
			(start -0.67945 0.3048)
			(end -0.67945 -0.305054)
			(stroke
				(width 0.1)
				(type default)
			)
			(layer "F.Fab")
		)
		(fp_line
			(start -0.12065 0.3048)
			(end -0.67945 0.3048)
			(stroke
				(width 0.1)
				(type default)
			)
			(layer "F.Fab")
		)
		(fp_line
			(start 0.120396 0.3048)
			(end 0.120396 0.2794)
			(stroke
				(width 0.1)
				(type default)
			)
			(layer "F.Fab")
		)
		(fp_line
			(start 0.67945 0.3048)
			(end 0.120396 0.3048)
			(stroke
				(width 0.1)
				(type default)
			)
			(layer "F.Fab")
		)
		(fp_line
			(start -0.12065 0.2794)
			(end -0.12065 0.3048)
			(stroke
				(width 0.1)
				(type default)
			)
			(layer "F.Fab")
		)
		(fp_line
			(start 0.120396 0.2794)
			(end -0.12065 0.2794)
			(stroke
				(width 0.1)
				(type default)
			)
			(layer "F.Fab")
		)
		(fp_line
			(start -0.12065 -0.2794)
			(end 0.12065 -0.2794)
			(stroke
				(width 0.1)
				(type default)
			)
			(layer "F.Fab")
		)
		(fp_line
			(start 0.12065 -0.2794)
			(end 0.12065 -0.3048)
			(stroke
				(width 0.1)
				(type default)
			)
			(layer "F.Fab")
		)
		(fp_line
			(start 0.12065 -0.3048)
			(end 0.67945 -0.3048)
			(stroke
				(width 0.1)
				(type default)
			)
			(layer "F.Fab")
		)
		(fp_line
			(start 0.67945 -0.3048)
			(end 0.67945 0.3048)
			(stroke
				(width 0.1)
				(type default)
			)
			(layer "F.Fab")
		)
		(fp_line
			(start -0.67945 -0.305054)
			(end -0.12065 -0.305054)
			(stroke
				(width 0.1)
				(type default)
			)
			(layer "F.Fab")
		)
		(fp_line
			(start -0.12065 -0.305054)
			(end -0.12065 -0.2794)
			(stroke
				(width 0.1)
				(type default)
			)
			(layer "F.Fab")
		)
		(pad "1" smd circle
			(at -0.40005 0 270)
			(size 0 0)
			(layers "F.Cu" "F.Mask" "F.Paste")
			(net "PVDDCR_CPU0_P1_VCC1")
		)
		(pad "2" smd circle
			(at 0.40005 0 270)
			(size 0 0)
			(layers "F.Cu" "F.Mask" "F.Paste")
			(net "GND")
		)
	)
	(footprint ""
		(layer "F.Cu")
		(at 106.932222 -15.22349)
		(property "Reference" "R4212"
			(at 0 0 0)
			(layer "F.SilkS")
			(hide yes)
			(effects
				(font
					(size 1.27 1.27)
				)
			)
		)
		(property "Value" ""
			(at 0 0 0)
			(layer "F.Fab")
			(effects
				(font
					(size 1.27 1.27)
				)
			)
		)
		(duplicate_pad_numbers_are_jumpers no)
		(fp_line
			(start -0.7874 -0.4064)
			(end 0.7874 -0.4064)
			(stroke
				(width 0.1524)
				(type default)
			)
			(layer "F.SilkS")
		)
		(fp_line
			(start -0.7874 0.4064)
			(end -0.7874 -0.4064)
			(stroke
				(width 0.1524)
				(type default)
			)
			(layer "F.SilkS")
		)
		(fp_line
			(start 0.7874 -0.4064)
			(end 0.7874 0.4064)
			(stroke
				(width 0.1524)
				(type default)
			)
			(layer "F.SilkS")
		)
		(fp_line
			(start 0.7874 0.4064)
			(end -0.7874 0.4064)
			(stroke
				(width 0.1524)
				(type default)
			)
			(layer "F.SilkS")
		)
		(fp_line
			(start -0.67945 -0.305054)
			(end -0.12065 -0.305054)
			(stroke
				(width 0.1)
				(type default)
			)
			(layer "F.Fab")
		)
		(fp_line
			(start -0.67945 0.3048)
			(end -0.67945 -0.305054)
			(stroke
				(width 0.1)
				(type default)
			)
			(layer "F.Fab")
		)
		(fp_line
			(start -0.12065 -0.305054)
			(end -0.12065 -0.2794)
			(stroke
				(width 0.1)
				(type default)
			)
			(layer "F.Fab")
		)
		(fp_line
			(start -0.12065 -0.2794)
			(end 0.12065 -0.2794)
			(stroke
				(width 0.1)
				(type default)
			)
			(layer "F.Fab")
		)
		(fp_line
			(start -0.12065 0.2794)
			(end -0.12065 0.3048)
			(stroke
				(width 0.1)
				(type default)
			)
			(layer "F.Fab")
		)
		(fp_line
			(start -0.12065 0.3048)
			(end -0.67945 0.3048)
			(stroke
				(width 0.1)
				(type default)
			)
			(layer "F.Fab")
		)
		(fp_line
			(start 0.120396 0.2794)
			(end -0.12065 0.2794)
			(stroke
				(width 0.1)
				(type default)
			)
			(layer "F.Fab")
		)
		(fp_line
			(start 0.120396 0.3048)
			(end 0.120396 0.2794)
			(stroke
				(width 0.1)
				(type default)
			)
			(layer "F.Fab")
		)
		(fp_line
			(start 0.12065 -0.3048)
			(end 0.67945 -0.3048)
			(stroke
				(width 0.1)
				(type default)
			)
			(layer "F.Fab")
		)
		(fp_line
			(start 0.12065 -0.2794)
			(end 0.12065 -0.3048)
			(stroke
				(width 0.1)
				(type default)
			)
			(layer "F.Fab")
		)
		(fp_line
			(start 0.67945 -0.3048)
			(end 0.67945 0.3048)
			(stroke
				(width 0.1)
				(type default)
			)
			(layer "F.Fab")
		)
		(fp_line
			(start 0.67945 0.3048)
			(end 0.120396 0.3048)
			(stroke
				(width 0.1)
				(type default)
			)
			(layer "F.Fab")
		)
		(pad "1" smd circle
			(at -0.40005 0)
			(size 0 0)
			(layers "F.Cu" "F.Mask" "F.Paste")
			(net "FM_THERMAL_ALERT_N")
		)
		(pad "2" smd circle
			(at 0.40005 0)
			(size 0 0)
			(layers "F.Cu" "F.Mask" "F.Paste")
			(net "FM_LM75_3_ALERT_N")
		)
	)
)
